# T6G (Grand Teton) — schematic netlist excerpt (pin names and nets, part order shuffled) for the footprints in the layout excerpt that follows; sources: Cadence DE-HDL packaged netlist, KiCad conversion of 04192023_DAF0TMB3IC0_F0TG_MB_C_brd_V02_OCP.brd

R8386  Q_RES  0 5% CHIP  pkg 0402LF  page 224 : A = PVDD11_S3_P1_EN ; B = PVDD11_S3_P1_EN_R
C1040  Q_CAP  22UF 4V 20% X6S  pkg C0402  page 312 : A = P0V9_CPU0_RT3_2A ; B = GND

(kicad_pcb
	(version 20260206)
	(generator "pcbnew")
	(generator_version "10.0")
	(general
		(thickness 1.6)
		(legacy_teardrops no)
	)
	(paper "A4")
	(title_block
		(title "04192023_DAF0TMB3IC0_F0TG_MB_C_brd_V02_OCP.brd")
		(comment 1 "Grand Teton / footprints 6135-6136 of 8354")
	)
	(layers
		(0 "F.Cu" signal "TOP")
		(4 "In1.Cu" signal "GND")
		(6 "In2.Cu" signal "IN1")
		(8 "In3.Cu" signal "GND1")
		(10 "In4.Cu" signal "IN2")
		(12 "In5.Cu" signal "GND2")
		(14 "In6.Cu" signal "IN3")
		(16 "In7.Cu" signal "GND3")
		(18 "In8.Cu" signal "VCC")
		(20 "In9.Cu" signal "VCC1")
		(22 "In10.Cu" signal "GND4")
		(24 "In11.Cu" signal "IN4")
		(26 "In12.Cu" signal "GND5")
		(28 "In13.Cu" signal "IN5")
		(30 "In14.Cu" signal "GND6")
		(32 "In15.Cu" signal "IN6")
		(34 "In16.Cu" signal "GND7")
		(2 "B.Cu" signal "BOTTOM")
		(9 "F.Adhes" user "F.Adhesive")
		(11 "B.Adhes" user "B.Adhesive")
		(13 "F.Paste" user "Package Geometry/Pastemask Top")
		(15 "B.Paste" user "Package Geometry/Pastemask Bottom")
		(5 "F.SilkS" user "Ref Des/Silkscreen Top")
		(7 "B.SilkS" user "Ref Des/Silkscreen Bottom")
		(1 "F.Mask" user "Board Geometry/Soldermask Top")
		(3 "B.Mask" user "Board Geometry/Soldermask Bottom")
		(17 "Dwgs.User" user "User.Drawings")
		(19 "Cmts.User" user "User.Comments")
		(21 "Eco1.User" user "User.Eco1")
		(23 "Eco2.User" user "User.Eco2")
		(25 "Edge.Cuts" user "Board Geometry/Outline")
		(27 "Margin" user)
		(31 "F.CrtYd" user "Package Geometry/Place Bound Top")
		(29 "B.CrtYd" user "Package Geometry/Place Bound Bottom")
		(35 "F.Fab" user "Ref Des/Assembly Top")
		(33 "B.Fab" user "Ref Des/Assembly Bottom")
	)
	(footprint ""
		(layer "B.Cu")
		(at 389.845296 -398.942052 90)
		(property "Reference" "C1040"
			(at 0 0 90)
			(layer "B.SilkS")
			(hide yes)
			(effects
				(font
					(size 1.27 1.27)
				)
				(justify mirror)
			)
		)
		(property "Value" ""
			(at 0 0 90)
			(layer "B.Fab")
			(effects
				(font
					(size 1.27 1.27)
				)
				(justify mirror)
			)
		)
		(duplicate_pad_numbers_are_jumpers no)
		(fp_line
			(start 0.7874 -0.4064)
			(end -0.7874 -0.4064)
			(stroke
				(width 0.1524)
				(type default)
			)
			(layer "B.SilkS")
		)
		(fp_line
			(start -0.7874 -0.4064)
			(end -0.7874 0.4064)
			(stroke
				(width 0.1524)
				(type default)
			)
			(layer "B.SilkS")
		)
		(fp_line
			(start 0.7874 0.4064)
			(end 0.7874 -0.4064)
			(stroke
				(width 0.1524)
				(type default)
			)
			(layer "B.SilkS")
		)
		(fp_line
			(start -0.7874 0.4064)
			(end 0.7874 0.4064)
			(stroke
				(width 0.1524)
				(type default)
			)
			(layer "B.SilkS")
		)
		(fp_line
			(start 0.67945 -0.305054)
			(end 0.12065 -0.305054)
			(stroke
				(width 0.1)
				(type default)
			)
			(layer "B.Fab")
		)
		(fp_line
			(start 0.12065 -0.305054)
			(end 0.12065 -0.2794)
			(stroke
				(width 0.1)
				(type default)
			)
			(layer "B.Fab")
		)
		(fp_line
			(start -0.12065 -0.3048)
			(end -0.67945 -0.3048)
			(stroke
				(width 0.1)
				(type default)
			)
			(layer "B.Fab")
		)
		(fp_line
			(start -0.67945 -0.3048)
			(end -0.67945 0.3048)
			(stroke
				(width 0.1)
				(type default)
			)
			(layer "B.Fab")
		)
		(fp_line
			(start 0.12065 -0.2794)
			(end -0.12065 -0.2794)
			(stroke
				(width 0.1)
				(type default)
			)
			(layer "B.Fab")
		)
		(fp_line
			(start -0.12065 -0.2794)
			(end -0.12065 -0.3048)
			(stroke
				(width 0.1)
				(type default)
			)
			(layer "B.Fab")
		)
		(fp_line
			(start 0.12065 0.2794)
			(end 0.12065 0.3048)
			(stroke
				(width 0.1)
				(type default)
			)
			(layer "B.Fab")
		)
		(fp_line
			(start -0.120396 0.2794)
			(end 0.12065 0.2794)
			(stroke
				(width 0.1)
				(type default)
			)
			(layer "B.Fab")
		)
		(fp_line
			(start 0.67945 0.3048)
			(end 0.67945 -0.305054)
			(stroke
				(width 0.1)
				(type default)
			)
			(layer "B.Fab")
		)
		(fp_line
			(start 0.12065 0.3048)
			(end 0.67945 0.3048)
			(stroke
				(width 0.1)
				(type default)
			)
			(layer "B.Fab")
		)
		(fp_line
			(start -0.120396 0.3048)
			(end -0.120396 0.2794)
			(stroke
				(width 0.1)
				(type default)
			)
			(layer "B.Fab")
		)
		(fp_line
			(start -0.67945 0.3048)
			(end -0.120396 0.3048)
			(stroke
				(width 0.1)
				(type default)
			)
			(layer "B.Fab")
		)
		(pad "1" smd circle
			(at 0.40005 0 270)
			(size 0 0)
			(layers "B.Cu" "B.Mask" "B.Paste")
			(net "P0V9_CPU0_RT3_2A")
		)
		(pad "2" smd circle
			(at -0.40005 0 270)
			(size 0 0)
			(layers "B.Cu" "B.Mask" "B.Paste")
			(net "GND")
		)
	)
	(footprint ""
		(layer "B.Cu")
		(at 157.026864 -350.289622 180)
		(property "Reference" "R8386"
			(at 0 0 0)
			(layer "B.SilkS")
			(hide yes)
			(effects
				(font
					(size 1.27 1.27)
				)
				(justify mirror)
			)
		)
		(property "Value" ""
			(at 0 0 0)
			(layer "B.Fab")
			(effects
				(font
					(size 1.27 1.27)
				)
				(justify mirror)
			)
		)
		(duplicate_pad_numbers_are_jumpers no)
		(fp_line
			(start 0.7874 0.4064)
			(end 0.7874 -0.4064)
			(stroke
				(width 0.1524)
				(type default)
			)
			(layer "B.SilkS")
		)
		(fp_line
			(start 0.7874 -0.4064)
			(end -0.7874 -0.4064)
			(stroke
				(width 0.1524)
				(type default)
			)
			(layer "B.SilkS")
		)
		(fp_line
			(start -0.7874 0.4064)
			(end 0.7874 0.4064)
			(stroke
				(width 0.1524)
				(type default)
			)
			(layer "B.SilkS")
		)
		(fp_line
			(start -0.7874 -0.4064)
			(end -0.7874 0.4064)
			(stroke
				(width 0.1524)
				(type default)
			)
			(layer "B.SilkS")
		)
		(fp_line
			(start 0.67945 0.3048)
			(end 0.67945 -0.305054)
			(stroke
				(width 0.1)
				(type default)
			)
			(layer "B.Fab")
		)
		(fp_line
			(start 0.67945 -0.305054)
			(end 0.12065 -0.305054)
			(stroke
				(width 0.1)
				(type default)
			)
			(layer "B.Fab")
		)
		(fp_line
			(start 0.12065 0.3048)
			(end 0.67945 0.3048)
			(stroke
				(width 0.1)
				(type default)
			)
			(layer "B.Fab")
		)
		(fp_line
			(start 0.12065 0.2794)
			(end 0.12065 0.3048)
			(stroke
				(width 0.1)
				(type default)
			)
			(layer "B.Fab")
		)
		(fp_line
			(start 0.12065 -0.2794)
			(end -0.12065 -0.2794)
			(stroke
				(width 0.1)
				(type default)
			)
			(layer "B.Fab")
		)
		(fp_line
			(start 0.12065 -0.305054)
			(end 0.12065 -0.2794)
			(stroke
				(width 0.1)
				(type default)
			)
			(layer "B.Fab")
		)
		(fp_line
			(start -0.120396 0.3048)
			(end -0.120396 0.2794)
			(stroke
				(width 0.1)
				(type default)
			)
			(layer "B.Fab")
		)
		(fp_line
			(start -0.120396 0.2794)
			(end 0.12065 0.2794)
			(stroke
				(width 0.1)
				(type default)
			)
			(layer "B.Fab")
		)
		(fp_line
			(start -0.12065 -0.2794)
			(end -0.12065 -0.3048)
			(stroke
				(width 0.1)
				(type default)
			)
			(layer "B.Fab")
		)
		(fp_line
			(start -0.12065 -0.3048)
			(end -0.67945 -0.3048)
			(stroke
				(width 0.1)
				(type default)
			)
			(layer "B.Fab")
		)
		(fp_line
			(start -0.67945 0.3048)
			(end -0.120396 0.3048)
			(stroke
				(width 0.1)
				(type default)
			)
			(layer "B.Fab")
		)
		(fp_line
			(start -0.67945 -0.3048)
			(end -0.67945 0.3048)
			(stroke
				(width 0.1)
				(type default)
			)
			(layer "B.Fab")
		)
		(pad "1" smd circle
			(at 0.40005 0)
			(size 0 0)
			(layers "B.Cu" "B.Mask" "B.Paste")
			(net "PVDD11_S3_P1_EN")
		)
		(pad "2" smd circle
			(at -0.40005 0)
			(size 0 0)
			(layers "B.Cu" "B.Mask" "B.Paste")
			(net "PVDD11_S3_P1_EN_R")
		)
	)
)
